# T6G (Grand Teton) — schematic netlist excerpt (pin names and nets, part order shuffled) for the footprints in the layout excerpt that follows; sources: Cadence DE-HDL packaged netlist, KiCad conversion of 04192023_DAF0TMB3IC0_F0TG_MB_C_brd_V02_OCP.brd

R3763  Q_RES  4.7K 1% CHIP  pkg 0402LF  page 236 : A = GND ; B = INA230_2_A1

U9001  74LVC1G08W57  74LVC1G08W5-7 IC  pkg SOT25-5_0-95_3X1-6  page 136
  A  = RST_PERST_OCP_SFF_R_N
  B  = HP_LVC3_OCP_V3_1_PWRGD
  GND  = GND
  Y  = RST_PERST_OCP_SFF_BUF_R_N
  VCC  = P3V3_AUX

(kicad_pcb
	(version 20260206)
	(generator "pcbnew")
	(generator_version "10.0")
	(general
		(thickness 1.6)
		(legacy_teardrops no)
	)
	(paper "A4")
	(title_block
		(title "04192023_DAF0TMB3IC0_F0TG_MB_C_brd_V02_OCP.brd")
		(comment 1 "Grand Teton / footprints 1244-1245 of 8354")
	)
	(layers
		(0 "F.Cu" signal "TOP")
		(4 "In1.Cu" signal "GND")
		(6 "In2.Cu" signal "IN1")
		(8 "In3.Cu" signal "GND1")
		(10 "In4.Cu" signal "IN2")
		(12 "In5.Cu" signal "GND2")
		(14 "In6.Cu" signal "IN3")
		(16 "In7.Cu" signal "GND3")
		(18 "In8.Cu" signal "VCC")
		(20 "In9.Cu" signal "VCC1")
		(22 "In10.Cu" signal "GND4")
		(24 "In11.Cu" signal "IN4")
		(26 "In12.Cu" signal "GND5")
		(28 "In13.Cu" signal "IN5")
		(30 "In14.Cu" signal "GND6")
		(32 "In15.Cu" signal "IN6")
		(34 "In16.Cu" signal "GND7")
		(2 "B.Cu" signal "BOTTOM")
		(9 "F.Adhes" user "F.Adhesive")
		(11 "B.Adhes" user "B.Adhesive")
		(13 "F.Paste" user "Package Geometry/Pastemask Top")
		(15 "B.Paste" user "Package Geometry/Pastemask Bottom")
		(5 "F.SilkS" user "Ref Des/Silkscreen Top")
		(7 "B.SilkS" user "Ref Des/Silkscreen Bottom")
		(1 "F.Mask" user "Board Geometry/Soldermask Top")
		(3 "B.Mask" user "Board Geometry/Soldermask Bottom")
		(17 "Dwgs.User" user "User.Drawings")
		(19 "Cmts.User" user "User.Comments")
		(21 "Eco1.User" user "User.Eco1")
		(23 "Eco2.User" user "User.Eco2")
		(25 "Edge.Cuts" user "Board Geometry/Outline")
		(27 "Margin" user)
		(31 "F.CrtYd" user "Package Geometry/Place Bound Top")
		(29 "B.CrtYd" user "Package Geometry/Place Bound Bottom")
		(35 "F.Fab" user "Ref Des/Assembly Top")
		(33 "B.Fab" user "Ref Des/Assembly Bottom")
	)
	(footprint ""
		(layer "F.Cu")
		(at 215.519 -119.888 90)
		(property "Reference" "U9001"
			(at -1.901444 4.060952 90)
			(unlocked yes)
			(layer "F.SilkS")
			(effects
				(font
					(size 0.7874 0.5842)
					(thickness 0.1524)
				)
				(justify left)
			)
		)
		(property "Value" ""
			(at 0 0 90)
			(layer "F.Fab")
			(effects
				(font
					(size 1.27 1.27)
				)
			)
		)
		(duplicate_pad_numbers_are_jumpers no)
		(fp_line
			(start 1.733296 -1.549908)
			(end 0.660908 -1.549908)
			(stroke
				(width 0.1524)
				(type default)
			)
			(layer "F.SilkS")
		)
		(fp_line
			(start 0.660908 -1.549908)
			(end 0 -0.889)
			(stroke
				(width 0.1524)
				(type default)
			)
			(layer "F.SilkS")
		)
		(fp_line
			(start -0.660908 -1.549908)
			(end -1.733296 -1.549908)
			(stroke
				(width 0.1524)
				(type default)
			)
			(layer "F.SilkS")
		)
		(fp_line
			(start -1.733296 -1.549908)
			(end -1.733296 1.549908)
			(stroke
				(width 0.1524)
				(type default)
			)
			(layer "F.SilkS")
		)
		(fp_line
			(start 0 -0.889)
			(end -0.660908 -1.549908)
			(stroke
				(width 0.1524)
				(type default)
			)
			(layer "F.SilkS")
		)
		(fp_line
			(start 1.733296 1.549908)
			(end 1.733296 -1.549908)
			(stroke
				(width 0.1524)
				(type default)
			)
			(layer "F.SilkS")
		)
		(fp_line
			(start -1.733296 1.549908)
			(end 1.733296 1.549908)
			(stroke
				(width 0.1524)
				(type default)
			)
			(layer "F.SilkS")
		)
		(fp_poly
			(pts
				(xy -2.4384 -1.20396) (xy -2.4384 -0.69596) (xy -1.9304 -0.94996)
			)
			(stroke
				(width 0)
				(type default)
			)
			(fill yes)
			(layer "F.SilkS")
		)
		(fp_line
			(start 0.849884 -1.549908)
			(end -0.849884 -1.549908)
			(stroke
				(width 0.1)
				(type default)
			)
			(layer "F.Fab")
		)
		(fp_line
			(start -0.849884 -1.549908)
			(end -0.849884 1.549908)
			(stroke
				(width 0.1)
				(type default)
			)
			(layer "F.Fab")
		)
		(fp_line
			(start 0.849884 1.549908)
			(end 0.849884 -1.549908)
			(stroke
				(width 0.1)
				(type default)
			)
			(layer "F.Fab")
		)
		(fp_line
			(start -0.849884 1.549908)
			(end 0.849884 1.549908)
			(stroke
				(width 0.1)
				(type default)
			)
			(layer "F.Fab")
		)
		(fp_poly
			(pts
				(xy -2.4384 -1.20396) (xy -2.4384 -0.69596) (xy -1.9304 -0.94996)
			)
			(stroke
				(width 0)
				(type default)
			)
			(fill yes)
			(layer "F.Fab")
		)
		(pad "1" smd rect
			(at -1.199896 -0.94996)
			(size 0.5588 0.8128)
			(layers "F.Cu" "F.Mask" "F.Paste")
			(net "RST_PERST_OCP_SFF_R_N")
		)
		(pad "2" smd rect
			(at -1.199896 0)
			(size 0.5588 0.8128)
			(layers "F.Cu" "F.Mask" "F.Paste")
			(net "HP_LVC3_OCP_V3_1_PWRGD")
		)
		(pad "3" smd rect
			(at -1.199896 0.94996)
			(size 0.5588 0.8128)
			(layers "F.Cu" "F.Mask" "F.Paste")
			(net "GND")
		)
		(pad "4" smd rect
			(at 1.199896 0.94996)
			(size 0.5588 0.8128)
			(layers "F.Cu" "F.Mask" "F.Paste")
			(net "RST_PERST_OCP_SFF_BUF_R_N")
		)
		(pad "5" smd rect
			(at 1.199896 -0.94996)
			(size 0.5588 0.8128)
			(layers "F.Cu" "F.Mask" "F.Paste")
			(net "P3V3_AUX")
		)
	)
	(footprint ""
		(layer "F.Cu")
		(at 211.76361 -57.548272 -90)
		(property "Reference" "R3763"
			(at 0 0 270)
			(layer "F.SilkS")
			(hide yes)
			(effects
				(font
					(size 1.27 1.27)
				)
			)
		)
		(property "Value" ""
			(at 0 0 270)
			(layer "F.Fab")
			(effects
				(font
					(size 1.27 1.27)
				)
			)
		)
		(duplicate_pad_numbers_are_jumpers no)
		(fp_line
			(start -0.7874 0.4064)
			(end -0.7874 -0.4064)
			(stroke
				(width 0.1524)
				(type default)
			)
			(layer "F.SilkS")
		)
		(fp_line
			(start 0.7874 0.4064)
			(end -0.7874 0.4064)
			(stroke
				(width 0.1524)
				(type default)
			)
			(layer "F.SilkS")
		)
		(fp_line
			(start -0.7874 -0.4064)
			(end 0.7874 -0.4064)
			(stroke
				(width 0.1524)
				(type default)
			)
			(layer "F.SilkS")
		)
		(fp_line
			(start 0.7874 -0.4064)
			(end 0.7874 0.4064)
			(stroke
				(width 0.1524)
				(type default)
			)
			(layer "F.SilkS")
		)
		(fp_line
			(start -0.67945 0.3048)
			(end -0.67945 -0.305054)
			(stroke
				(width 0.1)
				(type default)
			)
			(layer "F.Fab")
		)
		(fp_line
			(start -0.12065 0.3048)
			(end -0.67945 0.3048)
			(stroke
				(width 0.1)
				(type default)
			)
			(layer "F.Fab")
		)
		(fp_line
			(start 0.120396 0.3048)
			(end 0.120396 0.2794)
			(stroke
				(width 0.1)
				(type default)
			)
			(layer "F.Fab")
		)
		(fp_line
			(start 0.67945 0.3048)
			(end 0.120396 0.3048)
			(stroke
				(width 0.1)
				(type default)
			)
			(layer "F.Fab")
		)
		(fp_line
			(start -0.12065 0.2794)
			(end -0.12065 0.3048)
			(stroke
				(width 0.1)
				(type default)
			)
			(layer "F.Fab")
		)
		(fp_line
			(start 0.120396 0.2794)
			(end -0.12065 0.2794)
			(stroke
				(width 0.1)
				(type default)
			)
			(layer "F.Fab")
		)
		(fp_line
			(start -0.12065 -0.2794)
			(end 0.12065 -0.2794)
			(stroke
				(width 0.1)
				(type default)
			)
			(layer "F.Fab")
		)
		(fp_line
			(start 0.12065 -0.2794)
			(end 0.12065 -0.3048)
			(stroke
				(width 0.1)
				(type default)
			)
			(layer "F.Fab")
		)
		(fp_line
			(start 0.12065 -0.3048)
			(end 0.67945 -0.3048)
			(stroke
				(width 0.1)
				(type default)
			)
			(layer "F.Fab")
		)
		(fp_line
			(start 0.67945 -0.3048)
			(end 0.67945 0.3048)
			(stroke
				(width 0.1)
				(type default)
			)
			(layer "F.Fab")
		)
		(fp_line
			(start -0.67945 -0.305054)
			(end -0.12065 -0.305054)
			(stroke
				(width 0.1)
				(type default)
			)
			(layer "F.Fab")
		)
		(fp_line
			(start -0.12065 -0.305054)
			(end -0.12065 -0.2794)
			(stroke
				(width 0.1)
				(type default)
			)
			(layer "F.Fab")
		)
		(pad "1" smd circle
			(at -0.40005 0 270)
			(size 0 0)
			(layers "F.Cu" "F.Mask" "F.Paste")
			(net "GND")
		)
		(pad "2" smd circle
			(at 0.40005 0 270)
			(size 0 0)
			(layers "F.Cu" "F.Mask" "F.Paste")
			(net "INA230_2_A1")
		)
	)
)
